# T6G (Grand Teton) — schematic netlist excerpt (pin names and nets, part order shuffled) for the footprints in the layout excerpt that follows; sources: Cadence DE-HDL packaged netlist, KiCad conversion of 04192023_DAF0TMB3IC0_F0TG_MB_C_brd_V02_OCP.brd

PC284_3  Q_CAP  0.1UF 25V 10% X7R  pkg 0402  page 212 : A = PVDDCR_CPU0_P1_VCCS ; B = GND
R8160  Q_RES  1K 1% EMPTY  pkg 0402LF  page 210 : A = PVDD18_S5_P1 ; B = SVID_PVDDCR_CPU0_P1_SVC_R
C6637  Q_CAP_DIFFBUS  DIFF BUS_0.22UF 6.3V 20% X6S  pkg C0201  page 319 : \1\ = P5E_CPU1_P0_TX_BUF_C_DP<4> ; \2\ = P5E_CPU1_P0_TX_BUF_DP<4>

(kicad_pcb
	(version 20260206)
	(generator "pcbnew")
	(generator_version "10.0")
	(general
		(thickness 1.6)
		(legacy_teardrops no)
	)
	(paper "A4")
	(title_block
		(title "04192023_DAF0TMB3IC0_F0TG_MB_C_brd_V02_OCP.brd")
		(comment 1 "Grand Teton / footprints 3837-3839 of 8354")
	)
	(layers
		(0 "F.Cu" signal "TOP")
		(4 "In1.Cu" signal "GND")
		(6 "In2.Cu" signal "IN1")
		(8 "In3.Cu" signal "GND1")
		(10 "In4.Cu" signal "IN2")
		(12 "In5.Cu" signal "GND2")
		(14 "In6.Cu" signal "IN3")
		(16 "In7.Cu" signal "GND3")
		(18 "In8.Cu" signal "VCC")
		(20 "In9.Cu" signal "VCC1")
		(22 "In10.Cu" signal "GND4")
		(24 "In11.Cu" signal "IN4")
		(26 "In12.Cu" signal "GND5")
		(28 "In13.Cu" signal "IN5")
		(30 "In14.Cu" signal "GND6")
		(32 "In15.Cu" signal "IN6")
		(34 "In16.Cu" signal "GND7")
		(2 "B.Cu" signal "BOTTOM")
		(9 "F.Adhes" user "F.Adhesive")
		(11 "B.Adhes" user "B.Adhesive")
		(13 "F.Paste" user "Package Geometry/Pastemask Top")
		(15 "B.Paste" user "Package Geometry/Pastemask Bottom")
		(5 "F.SilkS" user "Ref Des/Silkscreen Top")
		(7 "B.SilkS" user "Ref Des/Silkscreen Bottom")
		(1 "F.Mask" user "Board Geometry/Soldermask Top")
		(3 "B.Mask" user "Board Geometry/Soldermask Bottom")
		(17 "Dwgs.User" user "User.Drawings")
		(19 "Cmts.User" user "User.Comments")
		(21 "Eco1.User" user "User.Eco1")
		(23 "Eco2.User" user "User.Eco2")
		(25 "Edge.Cuts" user "Board Geometry/Outline")
		(27 "Margin" user)
		(31 "F.CrtYd" user "Package Geometry/Place Bound Top")
		(29 "B.CrtYd" user "Package Geometry/Place Bound Bottom")
		(35 "F.Fab" user "Ref Des/Assembly Top")
		(33 "B.Fab" user "Ref Des/Assembly Bottom")
	)
	(footprint ""
		(layer "F.Cu")
		(at 60.936124 -408.517344 -90)
		(property "Reference" "C6637"
			(at 0 0 270)
			(layer "F.SilkS")
			(hide yes)
			(effects
				(font
					(size 1.27 1.27)
				)
			)
		)
		(property "Value" ""
			(at 0 0 270)
			(layer "F.Fab")
			(effects
				(font
					(size 1.27 1.27)
				)
			)
		)
		(duplicate_pad_numbers_are_jumpers no)
		(fp_line
			(start -0.299974 0.150114)
			(end -0.299974 -0.150114)
			(stroke
				(width 0.1)
				(type default)
			)
			(layer "F.Fab")
		)
		(fp_line
			(start 0.299974 0.150114)
			(end -0.299974 0.150114)
			(stroke
				(width 0.1)
				(type default)
			)
			(layer "F.Fab")
		)
		(fp_line
			(start -0.299974 -0.150114)
			(end 0.299974 -0.150114)
			(stroke
				(width 0.1)
				(type default)
			)
			(layer "F.Fab")
		)
		(fp_line
			(start 0.299974 -0.150114)
			(end 0.299974 0.150114)
			(stroke
				(width 0.1)
				(type default)
			)
			(layer "F.Fab")
		)
		(pad "1" smd rect
			(at -0.2667 0 270)
			(size 0.3048 0.381)
			(layers "F.Cu" "F.Mask" "F.Paste")
			(net "P5E_CPU1_P0_TX_BUF_C_DP<4>")
		)
		(pad "2" smd rect
			(at 0.2667 0 270)
			(size 0.3048 0.381)
			(layers "F.Cu" "F.Mask" "F.Paste")
			(net "P5E_CPU1_P0_TX_BUF_DP<4>")
		)
	)
	(footprint ""
		(layer "F.Cu")
		(at 90.209878 -147.93341 180)
		(property "Reference" "R8160"
			(at 0 0 180)
			(layer "F.SilkS")
			(hide yes)
			(effects
				(font
					(size 1.27 1.27)
				)
			)
		)
		(property "Value" ""
			(at 0 0 180)
			(layer "F.Fab")
			(effects
				(font
					(size 1.27 1.27)
				)
			)
		)
		(duplicate_pad_numbers_are_jumpers no)
		(fp_line
			(start 0.7874 0.4064)
			(end -0.7874 0.4064)
			(stroke
				(width 0.1524)
				(type default)
			)
			(layer "F.SilkS")
		)
		(fp_line
			(start 0.7874 -0.4064)
			(end 0.7874 0.4064)
			(stroke
				(width 0.1524)
				(type default)
			)
			(layer "F.SilkS")
		)
		(fp_line
			(start -0.7874 0.4064)
			(end -0.7874 -0.4064)
			(stroke
				(width 0.1524)
				(type default)
			)
			(layer "F.SilkS")
		)
		(fp_line
			(start -0.7874 -0.4064)
			(end 0.7874 -0.4064)
			(stroke
				(width 0.1524)
				(type default)
			)
			(layer "F.SilkS")
		)
		(fp_line
			(start 0.67945 0.3048)
			(end 0.120396 0.3048)
			(stroke
				(width 0.1)
				(type default)
			)
			(layer "F.Fab")
		)
		(fp_line
			(start 0.67945 -0.3048)
			(end 0.67945 0.3048)
			(stroke
				(width 0.1)
				(type default)
			)
			(layer "F.Fab")
		)
		(fp_line
			(start 0.12065 -0.2794)
			(end 0.12065 -0.3048)
			(stroke
				(width 0.1)
				(type default)
			)
			(layer "F.Fab")
		)
		(fp_line
			(start 0.12065 -0.3048)
			(end 0.67945 -0.3048)
			(stroke
				(width 0.1)
				(type default)
			)
			(layer "F.Fab")
		)
		(fp_line
			(start 0.120396 0.3048)
			(end 0.120396 0.2794)
			(stroke
				(width 0.1)
				(type default)
			)
			(layer "F.Fab")
		)
		(fp_line
			(start 0.120396 0.2794)
			(end -0.12065 0.2794)
			(stroke
				(width 0.1)
				(type default)
			)
			(layer "F.Fab")
		)
		(fp_line
			(start -0.12065 0.3048)
			(end -0.67945 0.3048)
			(stroke
				(width 0.1)
				(type default)
			)
			(layer "F.Fab")
		)
		(fp_line
			(start -0.12065 0.2794)
			(end -0.12065 0.3048)
			(stroke
				(width 0.1)
				(type default)
			)
			(layer "F.Fab")
		)
		(fp_line
			(start -0.12065 -0.2794)
			(end 0.12065 -0.2794)
			(stroke
				(width 0.1)
				(type default)
			)
			(layer "F.Fab")
		)
		(fp_line
			(start -0.12065 -0.305054)
			(end -0.12065 -0.2794)
			(stroke
				(width 0.1)
				(type default)
			)
			(layer "F.Fab")
		)
		(fp_line
			(start -0.67945 0.3048)
			(end -0.67945 -0.305054)
			(stroke
				(width 0.1)
				(type default)
			)
			(layer "F.Fab")
		)
		(fp_line
			(start -0.67945 -0.305054)
			(end -0.12065 -0.305054)
			(stroke
				(width 0.1)
				(type default)
			)
			(layer "F.Fab")
		)
		(pad "1" smd circle
			(at -0.40005 0 180)
			(size 0 0)
			(layers "F.Cu" "F.Mask" "F.Paste")
			(net "PVDD18_S5_P1")
		)
		(pad "2" smd circle
			(at 0.40005 0 180)
			(size 0 0)
			(layers "F.Cu" "F.Mask" "F.Paste")
			(net "SVID_PVDDCR_CPU0_P1_SVC_R")
		)
	)
	(footprint ""
		(layer "F.Cu")
		(at 101.767894 -177.83556 -90)
		(property "Reference" "PC284_3"
			(at 0 0 270)
			(layer "F.SilkS")
			(hide yes)
			(effects
				(font
					(size 1.27 1.27)
				)
			)
		)
		(property "Value" ""
			(at 0 0 270)
			(layer "F.Fab")
			(effects
				(font
					(size 1.27 1.27)
				)
			)
		)
		(duplicate_pad_numbers_are_jumpers no)
		(fp_line
			(start -0.7874 0.4064)
			(end -0.7874 -0.4064)
			(stroke
				(width 0.1524)
				(type default)
			)
			(layer "F.SilkS")
		)
		(fp_line
			(start 0.7874 0.4064)
			(end -0.7874 0.4064)
			(stroke
				(width 0.1524)
				(type default)
			)
			(layer "F.SilkS")
		)
		(fp_line
			(start -0.7874 -0.4064)
			(end 0.7874 -0.4064)
			(stroke
				(width 0.1524)
				(type default)
			)
			(layer "F.SilkS")
		)
		(fp_line
			(start 0.7874 -0.4064)
			(end 0.7874 0.4064)
			(stroke
				(width 0.1524)
				(type default)
			)
			(layer "F.SilkS")
		)
		(fp_line
			(start -0.67945 0.3048)
			(end -0.67945 -0.305054)
			(stroke
				(width 0.1)
				(type default)
			)
			(layer "F.Fab")
		)
		(fp_line
			(start -0.12065 0.3048)
			(end -0.67945 0.3048)
			(stroke
				(width 0.1)
				(type default)
			)
			(layer "F.Fab")
		)
		(fp_line
			(start 0.120396 0.3048)
			(end 0.120396 0.2794)
			(stroke
				(width 0.1)
				(type default)
			)
			(layer "F.Fab")
		)
		(fp_line
			(start 0.67945 0.3048)
			(end 0.120396 0.3048)
			(stroke
				(width 0.1)
				(type default)
			)
			(layer "F.Fab")
		)
		(fp_line
			(start -0.12065 0.2794)
			(end -0.12065 0.3048)
			(stroke
				(width 0.1)
				(type default)
			)
			(layer "F.Fab")
		)
		(fp_line
			(start 0.120396 0.2794)
			(end -0.12065 0.2794)
			(stroke
				(width 0.1)
				(type default)
			)
			(layer "F.Fab")
		)
		(fp_line
			(start -0.12065 -0.2794)
			(end 0.12065 -0.2794)
			(stroke
				(width 0.1)
				(type default)
			)
			(layer "F.Fab")
		)
		(fp_line
			(start 0.12065 -0.2794)
			(end 0.12065 -0.3048)
			(stroke
				(width 0.1)
				(type default)
			)
			(layer "F.Fab")
		)
		(fp_line
			(start 0.12065 -0.3048)
			(end 0.67945 -0.3048)
			(stroke
				(width 0.1)
				(type default)
			)
			(layer "F.Fab")
		)
		(fp_line
			(start 0.67945 -0.3048)
			(end 0.67945 0.3048)
			(stroke
				(width 0.1)
				(type default)
			)
			(layer "F.Fab")
		)
		(fp_line
			(start -0.67945 -0.305054)
			(end -0.12065 -0.305054)
			(stroke
				(width 0.1)
				(type default)
			)
			(layer "F.Fab")
		)
		(fp_line
			(start -0.12065 -0.305054)
			(end -0.12065 -0.2794)
			(stroke
				(width 0.1)
				(type default)
			)
			(layer "F.Fab")
		)
		(pad "1" smd circle
			(at -0.40005 0 270)
			(size 0 0)
			(layers "F.Cu" "F.Mask" "F.Paste")
			(net "PVDDCR_CPU0_P1_VCCS")
		)
		(pad "2" smd circle
			(at 0.40005 0 270)
			(size 0 0)
			(layers "F.Cu" "F.Mask" "F.Paste")
			(net "GND")
		)
	)
)
